# BASEBOARD_FAB2 (Tioga Pass) — schematic netlist excerpt (pin names and nets, part order shuffled) for the footprints in the layout excerpt that follows; sources: Cadence DE-HDL packaged netlist, KiCad conversion of Wiwynn_Tioga_Pass_MB.brd

R1U26  RES  5.11K 1% CHIP  pkg 0402  page 169 : A = P3V3 ; B = A_P3V3_SCALED
R6W39  RES  10.0K 1% CHIP  pkg 0402  page 176 : A = SPA_MID_DBG1_TX_EN ; B = P3V3_STBY
C8L2  CAP  100UF 4V 20% X5R  pkg 0805  page 228 : A = PVDDQ_KLM ; B = GND

(kicad_pcb
	(version 20260206)
	(generator "pcbnew")
	(generator_version "10.0")
	(general
		(thickness 1.6)
		(legacy_teardrops no)
	)
	(paper "A4")
	(title_block
		(title "Wiwynn_Tioga_Pass_MB.brd")
		(comment 1 "Tioga Pass / footprints 3869-3871 of 4770")
	)
	(layers
		(0 "F.Cu" signal "TOP")
		(4 "In1.Cu" signal "L2GND")
		(6 "In2.Cu" signal "L3")
		(8 "In3.Cu" signal "L4GND")
		(10 "In4.Cu" signal "L5")
		(12 "In5.Cu" signal "L6GND")
		(14 "In6.Cu" signal "L7VCC")
		(16 "In7.Cu" signal "L8VCC")
		(18 "In8.Cu" signal "L9GND")
		(20 "In9.Cu" signal "L10")
		(22 "In10.Cu" signal "L11GND")
		(24 "In11.Cu" signal "L12")
		(26 "In12.Cu" signal "L13GND")
		(2 "B.Cu" signal "BOTTOM")
		(9 "F.Adhes" user "F.Adhesive")
		(11 "B.Adhes" user "B.Adhesive")
		(13 "F.Paste" user "Package Geometry/Pastemask Top")
		(15 "B.Paste" user "Package Geometry/Pastemask Bottom")
		(5 "F.SilkS" user "Ref Des/Silkscreen Top")
		(7 "B.SilkS" user "Ref Des/Silkscreen Bottom")
		(1 "F.Mask" user "Board Geometry/Soldermask Top")
		(3 "B.Mask" user "Board Geometry/Soldermask Bottom")
		(17 "Dwgs.User" user "User.Drawings")
		(19 "Cmts.User" user "User.Comments")
		(21 "Eco1.User" user "User.Eco1")
		(23 "Eco2.User" user "User.Eco2")
		(25 "Edge.Cuts" user "Board Geometry/Outline")
		(27 "Margin" user)
		(31 "F.CrtYd" user "Package Geometry/Place Bound Top")
		(29 "B.CrtYd" user "Package Geometry/Place Bound Bottom")
		(35 "F.Fab" user "Ref Des/Assembly Top")
		(33 "B.Fab" user "Ref Des/Assembly Bottom")
	)
	(footprint ""
		(layer "B.Cu")
		(at 103.333296 -156.910024 -90)
		(property "Reference" "C8L2"
			(at 0 0 90)
			(layer "B.SilkS")
			(hide yes)
			(effects
				(font
					(size 1.27 1.27)
				)
				(justify mirror)
			)
		)
		(property "Value" ""
			(at 0 0 90)
			(layer "B.Fab")
			(effects
				(font
					(size 1.27 1.27)
				)
				(justify mirror)
			)
		)
		(duplicate_pad_numbers_are_jumpers no)
		(fp_poly
			(pts
				(xy 0.7239 -0.2159) (xy -0.7239 -0.2159) (xy -0.7239 1.9939) (xy 0.7239 1.9939)
			)
			(stroke
				(width 0)
				(type default)
			)
			(fill no)
			(layer "B.CrtYd")
		)
		(fp_line
			(start -0.7239 1.9939)
			(end -0.7239 -0.2159)
			(stroke
				(width 0.1)
				(type default)
			)
			(layer "B.Fab")
		)
		(fp_line
			(start 0.7239 1.9939)
			(end -0.7239 1.9939)
			(stroke
				(width 0.1)
				(type default)
			)
			(layer "B.Fab")
		)
		(fp_line
			(start -0.7239 -0.2159)
			(end 0.7239 -0.2159)
			(stroke
				(width 0.1)
				(type default)
			)
			(layer "B.Fab")
		)
		(fp_line
			(start 0.7239 -0.2159)
			(end 0.7239 1.9939)
			(stroke
				(width 0.1)
				(type default)
			)
			(layer "B.Fab")
		)
		(pad "1" smd rect
			(at 0 0 90)
			(size 1.27 1.016)
			(layers "B.Cu" "B.Mask" "B.Paste")
			(net "PVDDQ_KLM")
		)
		(pad "2" smd rect
			(at 0 1.778 90)
			(size 1.27 1.016)
			(layers "B.Cu" "B.Mask" "B.Paste")
			(net "GND")
		)
		(zone
			(layer "B.Cu")
			(hatch none 0.5)
			(connect_pads
				(clearance 0)
			)
			(min_thickness 0.25)
			(keepout
				(tracks not_allowed)
				(vias allowed)
				(pads allowed)
				(copperpour not_allowed)
				(footprints allowed)
			)
			(placement
				(enabled no)
				(sheetname "")
			)
			(fill
				(thermal_gap 0.5)
				(thermal_bridge_width 0.5)
				(island_removal_mode 0)
			)
			(polygon
				(pts
					(xy 102.825296 -156.275024) (xy 102.825296 -157.545024) (xy 102.063296 -157.545024) (xy 102.063296 -156.275024)
				)
			)
		)
	)
	(footprint ""
		(layer "B.Cu")
		(at 400.667474 -22.221698 180)
		(property "Reference" "R1U26"
			(at 0 0 0)
			(layer "B.SilkS")
			(hide yes)
			(effects
				(font
					(size 1.27 1.27)
				)
				(justify mirror)
			)
		)
		(property "Value" ""
			(at 0 0 0)
			(layer "B.Fab")
			(effects
				(font
					(size 1.27 1.27)
				)
				(justify mirror)
			)
		)
		(duplicate_pad_numbers_are_jumpers no)
		(fp_poly
			(pts
				(xy 0.2794 -0.1016) (xy -0.2794 -0.1016) (xy -0.2794 0.9906) (xy 0.2794 0.9906)
			)
			(stroke
				(width 0)
				(type default)
			)
			(fill no)
			(layer "B.CrtYd")
		)
		(fp_line
			(start 0.2794 0.9906)
			(end -0.2794 0.9906)
			(stroke
				(width 0.1)
				(type default)
			)
			(layer "B.Fab")
		)
		(fp_line
			(start 0.2794 -0.1016)
			(end 0.2794 0.9906)
			(stroke
				(width 0.1)
				(type default)
			)
			(layer "B.Fab")
		)
		(fp_line
			(start -0.2794 0.9906)
			(end -0.2794 -0.1016)
			(stroke
				(width 0.1)
				(type default)
			)
			(layer "B.Fab")
		)
		(fp_line
			(start -0.2794 -0.1016)
			(end 0.2794 -0.1016)
			(stroke
				(width 0.1)
				(type default)
			)
			(layer "B.Fab")
		)
		(pad "1" smd rect
			(at 0 0)
			(size 0.508 0.508)
			(layers "B.Cu" "B.Mask" "B.Paste")
			(net "P3V3")
		)
		(pad "2" smd rect
			(at 0 0.889)
			(size 0.508 0.508)
			(layers "B.Cu" "B.Mask" "B.Paste")
			(net "A_P3V3_SCALED")
		)
		(zone
			(layer "B.Cu")
			(hatch none 0.5)
			(connect_pads
				(clearance 0)
			)
			(min_thickness 0.25)
			(keepout
				(tracks not_allowed)
				(vias allowed)
				(pads allowed)
				(copperpour not_allowed)
				(footprints allowed)
			)
			(placement
				(enabled no)
				(sheetname "")
			)
			(fill
				(thermal_gap 0.5)
				(thermal_bridge_width 0.5)
				(island_removal_mode 0)
			)
			(polygon
				(pts
					(xy 400.413474 -22.856698) (xy 400.921474 -22.856698) (xy 400.921474 -22.475698) (xy 400.413474 -22.475698)
				)
			)
		)
		(zone
			(layer "B.Cu")
			(hatch none 0.5)
			(connect_pads
				(clearance 0)
			)
			(min_thickness 0.25)
			(keepout
				(tracks allowed)
				(vias not_allowed)
				(pads allowed)
				(copperpour not_allowed)
				(footprints allowed)
			)
			(placement
				(enabled no)
				(sheetname "")
			)
			(fill
				(thermal_gap 0.5)
				(thermal_bridge_width 0.5)
				(island_removal_mode 0)
			)
			(polygon
				(pts
					(xy 400.413474 -22.475698) (xy 400.921474 -22.475698) (xy 400.921474 -22.856698) (xy 400.413474 -22.856698)
				)
			)
		)
	)
	(footprint ""
		(layer "B.Cu")
		(at 500.3292 -146.8374)
		(property "Reference" "R6W39"
			(at 0.8382 -0.67818 0)
			(unlocked yes)
			(layer "B.SilkS")
			(effects
				(font
					(size 0.4064 0.254)
					(thickness 0.1524)
				)
				(justify left mirror)
			)
		)
		(property "Value" ""
			(at 0 0 0)
			(layer "B.Fab")
			(effects
				(font
					(size 1.27 1.27)
				)
				(justify mirror)
			)
		)
		(duplicate_pad_numbers_are_jumpers no)
		(fp_poly
			(pts
				(xy 0.2794 -0.1016) (xy -0.2794 -0.1016) (xy -0.2794 0.9906) (xy 0.2794 0.9906)
			)
			(stroke
				(width 0)
				(type default)
			)
			(fill no)
			(layer "B.CrtYd")
		)
		(fp_line
			(start -0.2794 -0.1016)
			(end 0.2794 -0.1016)
			(stroke
				(width 0.1)
				(type default)
			)
			(layer "B.Fab")
		)
		(fp_line
			(start -0.2794 0.9906)
			(end -0.2794 -0.1016)
			(stroke
				(width 0.1)
				(type default)
			)
			(layer "B.Fab")
		)
		(fp_line
			(start 0.2794 -0.1016)
			(end 0.2794 0.9906)
			(stroke
				(width 0.1)
				(type default)
			)
			(layer "B.Fab")
		)
		(fp_line
			(start 0.2794 0.9906)
			(end -0.2794 0.9906)
			(stroke
				(width 0.1)
				(type default)
			)
			(layer "B.Fab")
		)
		(pad "1" smd rect
			(at 0 0 180)
			(size 0.508 0.508)
			(layers "B.Cu" "B.Mask" "B.Paste")
			(net "SPA_MID_DBG1_TX_EN")
		)
		(pad "2" smd rect
			(at 0 0.889 180)
			(size 0.508 0.508)
			(layers "B.Cu" "B.Mask" "B.Paste")
			(net "P3V3_STBY")
		)
		(zone
			(layer "B.Cu")
			(hatch none 0.5)
			(connect_pads
				(clearance 0)
			)
			(min_thickness 0.25)
			(keepout
				(tracks allowed)
				(vias not_allowed)
				(pads allowed)
				(copperpour not_allowed)
				(footprints allowed)
			)
			(placement
				(enabled no)
				(sheetname "")
			)
			(fill
				(thermal_gap 0.5)
				(thermal_bridge_width 0.5)
				(island_removal_mode 0)
			)
			(polygon
				(pts
					(xy 500.5832 -146.5834) (xy 500.0752 -146.5834) (xy 500.0752 -146.2024) (xy 500.5832 -146.2024)
				)
			)
		)
		(zone
			(layer "B.Cu")
			(hatch none 0.5)
			(connect_pads
				(clearance 0)
			)
			(min_thickness 0.25)
			(keepout
				(tracks not_allowed)
				(vias allowed)
				(pads allowed)
				(copperpour not_allowed)
				(footprints allowed)
			)
			(placement
				(enabled no)
				(sheetname "")
			)
			(fill
				(thermal_gap 0.5)
				(thermal_bridge_width 0.5)
				(island_removal_mode 0)
			)
			(polygon
				(pts
					(xy 500.5832 -146.2024) (xy 500.0752 -146.2024) (xy 500.0752 -146.5834) (xy 500.5832 -146.5834)
				)
			)
		)
	)
)
